(kicad_pcb
	(version 20241229)
	(generator "pcbnew")
	(generator_version "9.0")
	(general
		(thickness 1.599998)
		(legacy_teardrops no)
	)
	(paper "A4")
	(title_block
		(title "Artix - Datacenter Secure Control Module (DC-SCM)")
		(date "2024-11-06")
		(rev "1.1.3")
		(comment 9 "footprints 223-227 of 544")
	)
	(layers
		(0 "F.Cu" signal)
		(4 "In1.Cu" signal)
		(6 "In2.Cu" signal)
		(8 "In3.Cu" signal)
		(10 "In4.Cu" signal)
		(12 "In5.Cu" signal)
		(14 "In6.Cu" signal)
		(2 "B.Cu" signal)
		(9 "F.Adhes" user "F.Adhesive")
		(11 "B.Adhes" user "B.Adhesive")
		(13 "F.Paste" user)
		(15 "B.Paste" user)
		(5 "F.SilkS" user "F.Silkscreen")
		(7 "B.SilkS" user "B.Silkscreen")
		(1 "F.Mask" user)
		(3 "B.Mask" user)
		(17 "Dwgs.User" user "User.Drawings")
		(19 "Cmts.User" user "User.Comments")
		(21 "Eco1.User" user "User.Eco1")
		(23 "Eco2.User" user "User.Eco2")
		(25 "Edge.Cuts" user)
		(27 "Margin" user)
		(31 "F.CrtYd" user "F.Courtyard")
		(29 "B.CrtYd" user "B.Courtyard")
		(35 "F.Fab" user)
		(33 "B.Fab" user)
	)
	(footprint "antmicro-footprints:USON-14_3.5x1.35_P0.5mm"
		(layer "F.Cu")
		(at 137.515 75.265 -90)
		(descr "JEDEC MO-229")
		(property "Reference" "D2"
			(at -1.065 0.815 0)
			(layer "F.SilkS")
			(effects
				(font
					(size 0.7 0.7)
					(thickness 0.15)
				)
				(justify left bottom)
			)
		)
		(property "Value" "SP3011-06UTG"
			(at -1.3 3 270)
			(layer "F.Fab")
			(effects
				(font
					(size 0.7 0.7)
					(thickness 0.15)
				)
				(justify left bottom)
			)
		)
		(property "Datasheet" "https://www.littelfuse.com/media?resourcetype=datasheets&itemid=c9002a97-9994-449b-b722-f45ab5538c7f&filename=littelfuse-tvs-diode-array-sp3011-datasheet"
			(at 0 0 270)
			(layer "F.Fab")
			(hide yes)
			(effects
				(font
					(size 1.27 1.27)
					(thickness 0.15)
				)
			)
		)
		(property "Description" "TVS diode array, 8 kV, USON-14, 6 V, 0.4 pF"
			(at 0 0 270)
			(layer "F.Fab")
			(hide yes)
			(effects
				(font
					(size 1.27 1.27)
					(thickness 0.15)
				)
			)
		)
		(property "Author" "Antmicro"
			(at 62.25 212.78 0)
			(layer "F.Fab")
			(hide yes)
			(effects
				(font
					(size 1 1)
					(thickness 0.15)
				)
			)
		)
		(property "License" "Apache-2.0"
			(at 62.25 212.78 0)
			(layer "F.Fab")
			(hide yes)
			(effects
				(font
					(size 1 1)
					(thickness 0.15)
				)
			)
		)
		(property "MPN" "SP3011-06UTG"
			(at 62.25 212.78 0)
			(layer "F.Fab")
			(hide yes)
			(effects
				(font
					(size 1 1)
					(thickness 0.15)
				)
			)
		)
		(property "Manufacturer" "Littelfuse"
			(at 62.25 212.78 0)
			(layer "F.Fab")
			(hide yes)
			(effects
				(font
					(size 1 1)
					(thickness 0.15)
				)
			)
		)
		(sheetname "/Interfaces/")
		(sheetfile "interfaces.kicad_sch")
		(attr smd)
		(fp_line
			(start -0.8 1.75)
			(end 0.8 1.75)
			(stroke
				(width 0.12)
				(type solid)
			)
			(layer "F.SilkS")
		)
		(fp_line
			(start -0.4 -1.75)
			(end 0.8 -1.75)
			(stroke
				(width 0.12)
				(type solid)
			)
			(layer "F.SilkS")
		)
		(fp_rect
			(start 1 -1.9)
			(end -0.95 1.9)
			(stroke
				(width 0.05)
				(type solid)
			)
			(fill no)
			(layer "F.CrtYd")
		)
		(fp_line
			(start -0.7 1.75)
			(end -0.7 -1.55)
			(stroke
				(width 0.1)
				(type solid)
			)
			(layer "F.Fab")
		)
		(fp_line
			(start 0.65 1.75)
			(end -0.7 1.75)
			(stroke
				(width 0.1)
				(type solid)
			)
			(layer "F.Fab")
		)
		(fp_line
			(start -0.7 -1.55)
			(end -0.5 -1.75)
			(stroke
				(width 0.1)
				(type solid)
			)
			(layer "F.Fab")
		)
		(fp_line
			(start -0.5 -1.75)
			(end 0.65 -1.75)
			(stroke
				(width 0.1)
				(type solid)
			)
			(layer "F.Fab")
		)
		(fp_line
			(start 0.65 -1.75)
			(end 0.65 1.75)
			(stroke
				(width 0.1)
				(type solid)
			)
			(layer "F.Fab")
		)
		(fp_text user "."
			(at -0.9 -2.25 270)
			(layer "F.SilkS")
			(effects
				(font
					(size 1 1)
					(thickness 0.15)
				)
			)
		)
		(pad "1" smd roundrect
			(at -0.623 -1.5 180)
			(size 0.2 0.5)
			(layers "F.Cu" "F.Mask" "F.Paste")
			(roundrect_rratio 0.25)
			(chamfer_ratio 0.2)
			(chamfer bottom_left)
			(net 16 "JTAG_TMS")
			(pintype "passive")
		)
		(pad "2" smd roundrect
			(at -0.623 -1 180)
			(size 0.2 0.5)
			(layers "F.Cu" "F.Mask" "F.Paste")
			(roundrect_rratio 0.25)
			(net 15 "JTAG_TCK")
			(pintype "passive")
		)
		(pad "3" smd roundrect
			(at -0.623 -0.5 180)
			(size 0.2 0.5)
			(layers "F.Cu" "F.Mask" "F.Paste")
			(roundrect_rratio 0.25)
			(net 695 "unconnected-(D2-Pad12)_1")
			(pintype "passive+no_connect")
		)
		(pad "4" smd roundrect
			(at -0.623 0 180)
			(size 0.2 0.5)
			(layers "F.Cu" "F.Mask" "F.Paste")
			(roundrect_rratio 0.25)
			(net 696 "unconnected-(D2-Pad11)_1")
			(pintype "passive+no_connect")
		)
		(pad "5" smd roundrect
			(at -0.623 0.498 180)
			(size 0.2 0.5)
			(layers "F.Cu" "F.Mask" "F.Paste")
			(roundrect_rratio 0.25)
			(net 1 "GND")
			(pintype "passive")
		)
		(pad "6" smd roundrect
			(at -0.623 0.998 180)
			(size 0.2 0.5)
			(layers "F.Cu" "F.Mask" "F.Paste")
			(roundrect_rratio 0.25)
			(net 14 "JTAG_TDO")
			(pintype "passive")
		)
		(pad "7" smd roundrect
			(at -0.623 1.499 180)
			(size 0.2 0.5)
			(layers "F.Cu" "F.Mask" "F.Paste")
			(roundrect_rratio 0.25)
			(net 13 "JTAG_TDI")
			(pintype "passive")
		)
		(pad "8" smd roundrect
			(at 0.625 1.499 180)
			(size 0.2 0.5)
			(layers "F.Cu" "F.Mask" "F.Paste")
			(roundrect_rratio 0.25)
			(net 13 "JTAG_TDI")
			(pintype "passive")
		)
		(pad "9" smd roundrect
			(at 0.625 0.998 180)
			(size 0.2 0.5)
			(layers "F.Cu" "F.Mask" "F.Paste")
			(roundrect_rratio 0.25)
			(net 14 "JTAG_TDO")
			(pintype "passive")
		)
		(pad "10" smd roundrect
			(at 0.625 0.498 180)
			(size 0.2 0.5)
			(layers "F.Cu" "F.Mask" "F.Paste")
			(roundrect_rratio 0.25)
			(net 1 "GND")
			(pintype "passive")
		)
		(pad "11" smd roundrect
			(at 0.625 0 180)
			(size 0.2 0.5)
			(layers "F.Cu" "F.Mask" "F.Paste")
			(roundrect_rratio 0.25)
			(net 210 "unconnected-(D2-Pad11)")
			(pintype "passive+no_connect")
		)
		(pad "12" smd roundrect
			(at 0.625 -0.5 180)
			(size 0.2 0.5)
			(layers "F.Cu" "F.Mask" "F.Paste")
			(roundrect_rratio 0.25)
			(net 209 "unconnected-(D2-Pad12)")
			(pintype "passive+no_connect")
		)
		(pad "13" smd roundrect
			(at 0.625 -1 180)
			(size 0.2 0.5)
			(layers "F.Cu" "F.Mask" "F.Paste")
			(roundrect_rratio 0.25)
			(net 15 "JTAG_TCK")
			(pintype "passive")
		)
		(pad "14" smd roundrect
			(at 0.625 -1.5 180)
			(size 0.2 0.5)
			(layers "F.Cu" "F.Mask" "F.Paste")
			(roundrect_rratio 0.25)
			(net 16 "JTAG_TMS")
			(pintype "passive")
		)
	)
	(footprint "antmicro-footprints:C_0402_1005Metric"
		(layer "F.Cu")
		(at 83.09 167.05 -90)
		(descr "Capacitor SMD 0402")
		(tags "capacitor SMD 0402")
		(property "Reference" "C253"
			(at -0.65 0.49 90)
			(layer "F.SilkS")
			(effects
				(font
					(size 0.7 0.7)
					(thickness 0.15)
				)
				(justify right bottom)
			)
		)
		(property "Value" "C_100n_0402"
			(at 0 1.4 90)
			(layer "F.Fab")
			(effects
				(font
					(size 0.7 0.7)
					(thickness 0.15)
				)
				(justify right bottom)
			)
		)
		(property "Datasheet" "https://www.murata.com/products/productdetail?partno=GRM155R61H104KE14%23"
			(at 0 0 270)
			(layer "F.Fab")
			(hide yes)
			(effects
				(font
					(size 1.27 1.27)
					(thickness 0.15)
				)
			)
		)
		(property "Description" "SMD Multilayer Ceramic Capacitor, 0.1 µF, 50 V, 0402 [1005 Metric], ± 10%, X5R, GRM Series"
			(at 0 0 270)
			(layer "F.Fab")
			(hide yes)
			(effects
				(font
					(size 1.27 1.27)
					(thickness 0.15)
				)
			)
		)
		(property "Author" "Antmicro"
			(at -83.96 250.14 0)
			(layer "F.Fab")
			(hide yes)
			(effects
				(font
					(size 1 1)
					(thickness 0.15)
				)
			)
		)
		(property "Dielectric" "X5R"
			(at -83.96 250.14 0)
			(layer "F.Fab")
			(hide yes)
			(effects
				(font
					(size 1 1)
					(thickness 0.15)
				)
			)
		)
		(property "License" "Apache-2.0"
			(at -83.96 250.14 0)
			(layer "F.Fab")
			(hide yes)
			(effects
				(font
					(size 1 1)
					(thickness 0.15)
				)
			)
		)
		(property "MPN" "GRM155R61H104KE14D"
			(at -83.96 250.14 0)
			(layer "F.Fab")
			(hide yes)
			(effects
				(font
					(size 1 1)
					(thickness 0.15)
				)
			)
		)
		(property "Manufacturer" "Murata"
			(at -83.96 250.14 0)
			(layer "F.Fab")
			(hide yes)
			(effects
				(font
					(size 1 1)
					(thickness 0.15)
				)
			)
		)
		(property "Val" "100n"
			(at -83.96 250.14 0)
			(layer "F.Fab")
			(hide yes)
			(effects
				(font
					(size 1 1)
					(thickness 0.15)
				)
			)
		)
		(property "Voltage" "50V"
			(at -83.96 250.14 0)
			(layer "F.Fab")
			(hide yes)
			(effects
				(font
					(size 1 1)
					(thickness 0.15)
				)
			)
		)
		(sheetname "/Interfaces/")
		(sheetfile "interfaces.kicad_sch")
		(attr smd)
		(fp_rect
			(start -0.925 -0.47)
			(end 0.925 0.47)
			(stroke
				(width 0.05)
				(type default)
			)
			(fill no)
			(layer "F.CrtYd")
		)
		(fp_line
			(start -0.494 0.248)
			(end -0.494 -0.25)
			(stroke
				(width 0.15)
				(type solid)
			)
			(layer "F.Fab")
		)
		(fp_line
			(start 0.504 0.248)
			(end -0.494 0.248)
			(stroke
				(width 0.15)
				(type solid)
			)
			(layer "F.Fab")
		)
		(fp_line
			(start -0.494 -0.25)
			(end 0.504 -0.25)
			(stroke
				(width 0.15)
				(type solid)
			)
			(layer "F.Fab")
		)
		(fp_line
			(start 0.504 -0.25)
			(end 0.504 0.248)
			(stroke
				(width 0.15)
				(type solid)
			)
			(layer "F.Fab")
		)
		(pad "1" smd roundrect
			(at -0.48 0 270)
			(size 0.59 0.64)
			(layers "F.Cu" "F.Mask" "F.Paste")
			(roundrect_rratio 0.25)
			(net 1 "GND")
			(pintype "passive")
		)
		(pad "2" smd roundrect
			(at 0.48 0 270)
			(size 0.59 0.64)
			(layers "F.Cu" "F.Mask" "F.Paste")
			(roundrect_rratio 0.25)
			(net 5 "VCC1V8")
			(pintype "passive")
		)
	)
	(footprint "antmicro-footprints:C_0402_1005Metric"
		(layer "F.Cu")
		(at 92.065 163.425 90)
		(descr "Capacitor SMD 0402")
		(tags "capacitor SMD 0402")
		(property "Reference" "C254"
			(at -0.975 1.335 90)
			(layer "F.SilkS")
			(effects
				(font
					(size 0.7 0.7)
					(thickness 0.15)
				)
				(justify left bottom)
			)
		)
		(property "Value" "C_100n_0402"
			(at 0 1.4 90)
			(layer "F.Fab")
			(effects
				(font
					(size 0.7 0.7)
					(thickness 0.15)
				)
				(justify left bottom)
			)
		)
		(property "Datasheet" "https://www.murata.com/products/productdetail?partno=GRM155R61H104KE14%23"
			(at 0 0 90)
			(layer "F.Fab")
			(hide yes)
			(effects
				(font
					(size 1.27 1.27)
					(thickness 0.15)
				)
			)
		)
		(property "Description" "SMD Multilayer Ceramic Capacitor, 0.1 µF, 50 V, 0402 [1005 Metric], ± 10%, X5R, GRM Series"
			(at 0 0 90)
			(layer "F.Fab")
			(hide yes)
			(effects
				(font
					(size 1.27 1.27)
					(thickness 0.15)
				)
			)
		)
		(property "Author" "Antmicro"
			(at 255.49 71.36 0)
			(layer "F.Fab")
			(hide yes)
			(effects
				(font
					(size 1 1)
					(thickness 0.15)
				)
			)
		)
		(property "Dielectric" "X5R"
			(at 255.49 71.36 0)
			(layer "F.Fab")
			(hide yes)
			(effects
				(font
					(size 1 1)
					(thickness 0.15)
				)
			)
		)
		(property "License" "Apache-2.0"
			(at 255.49 71.36 0)
			(layer "F.Fab")
			(hide yes)
			(effects
				(font
					(size 1 1)
					(thickness 0.15)
				)
			)
		)
		(property "MPN" "GRM155R61H104KE14D"
			(at 255.49 71.36 0)
			(layer "F.Fab")
			(hide yes)
			(effects
				(font
					(size 1 1)
					(thickness 0.15)
				)
			)
		)
		(property "Manufacturer" "Murata"
			(at 255.49 71.36 0)
			(layer "F.Fab")
			(hide yes)
			(effects
				(font
					(size 1 1)
					(thickness 0.15)
				)
			)
		)
		(property "Val" "100n"
			(at 255.49 71.36 0)
			(layer "F.Fab")
			(hide yes)
			(effects
				(font
					(size 1 1)
					(thickness 0.15)
				)
			)
		)
		(property "Voltage" "50V"
			(at 255.49 71.36 0)
			(layer "F.Fab")
			(hide yes)
			(effects
				(font
					(size 1 1)
					(thickness 0.15)
				)
			)
		)
		(sheetname "/Interfaces/")
		(sheetfile "interfaces.kicad_sch")
		(attr smd)
		(fp_rect
			(start -0.925 -0.47)
			(end 0.925 0.47)
			(stroke
				(width 0.05)
				(type default)
			)
			(fill no)
			(layer "F.CrtYd")
		)
		(fp_line
			(start 0.504 -0.25)
			(end 0.504 0.248)
			(stroke
				(width 0.15)
				(type solid)
			)
			(layer "F.Fab")
		)
		(fp_line
			(start -0.494 -0.25)
			(end 0.504 -0.25)
			(stroke
				(width 0.15)
				(type solid)
			)
			(layer "F.Fab")
		)
		(fp_line
			(start 0.504 0.248)
			(end -0.494 0.248)
			(stroke
				(width 0.15)
				(type solid)
			)
			(layer "F.Fab")
		)
		(fp_line
			(start -0.494 0.248)
			(end -0.494 -0.25)
			(stroke
				(width 0.15)
				(type solid)
			)
			(layer "F.Fab")
		)
		(pad "1" smd roundrect
			(at -0.48 0 90)
			(size 0.59 0.64)
			(layers "F.Cu" "F.Mask" "F.Paste")
			(roundrect_rratio 0.25)
			(net 1 "GND")
			(pintype "passive")
		)
		(pad "2" smd roundrect
			(at 0.48 0 90)
			(size 0.59 0.64)
			(layers "F.Cu" "F.Mask" "F.Paste")
			(roundrect_rratio 0.25)
			(net 5 "VCC1V8")
			(pintype "passive")
		)
	)
	(footprint "antmicro-footprints:C_0402_1005Metric"
		(layer "F.Cu")
		(at 120.965 133.125 90)
		(descr "Capacitor SMD 0402")
		(tags "capacitor SMD 0402")
		(property "Reference" "C4"
			(at -0.775 -0.465 90)
			(layer "F.SilkS")
			(effects
				(font
					(size 0.7 0.7)
					(thickness 0.15)
				)
				(justify left bottom)
			)
		)
		(property "Value" "C_100n_0402"
			(at 0 1.4 90)
			(layer "F.Fab")
			(effects
				(font
					(size 0.7 0.7)
					(thickness 0.15)
				)
				(justify left bottom)
			)
		)
		(property "Datasheet" "https://www.murata.com/products/productdetail?partno=GRM155R61H104KE14%23"
			(at 0 0 90)
			(layer "F.Fab")
			(hide yes)
			(effects
				(font
					(size 1.27 1.27)
					(thickness 0.15)
				)
			)
		)
		(property "Description" "SMD Multilayer Ceramic Capacitor, 0.1 µF, 50 V, 0402 [1005 Metric], ± 10%, X5R, GRM Series"
			(at 0 0 90)
			(layer "F.Fab")
			(hide yes)
			(effects
				(font
					(size 1.27 1.27)
					(thickness 0.15)
				)
			)
		)
		(property "Author" "Antmicro"
			(at 254.09 12.16 0)
			(layer "F.Fab")
			(hide yes)
			(effects
				(font
					(size 1 1)
					(thickness 0.15)
				)
			)
		)
		(property "Dielectric" "X5R"
			(at 254.09 12.16 0)
			(layer "F.Fab")
			(hide yes)
			(effects
				(font
					(size 1 1)
					(thickness 0.15)
				)
			)
		)
		(property "License" "Apache-2.0"
			(at 254.09 12.16 0)
			(layer "F.Fab")
			(hide yes)
			(effects
				(font
					(size 1 1)
					(thickness 0.15)
				)
			)
		)
		(property "MPN" "GRM155R61H104KE14D"
			(at 254.09 12.16 0)
			(layer "F.Fab")
			(hide yes)
			(effects
				(font
					(size 1 1)
					(thickness 0.15)
				)
			)
		)
		(property "Manufacturer" "Murata"
			(at 254.09 12.16 0)
			(layer "F.Fab")
			(hide yes)
			(effects
				(font
					(size 1 1)
					(thickness 0.15)
				)
			)
		)
		(property "Val" "100n"
			(at 254.09 12.16 0)
			(layer "F.Fab")
			(hide yes)
			(effects
				(font
					(size 1 1)
					(thickness 0.15)
				)
			)
		)
		(property "Voltage" "50V"
			(at 254.09 12.16 0)
			(layer "F.Fab")
			(hide yes)
			(effects
				(font
					(size 1 1)
					(thickness 0.15)
				)
			)
		)
		(sheetname "/Interfaces/")
		(sheetfile "interfaces.kicad_sch")
		(attr smd)
		(fp_rect
			(start -0.925 -0.47)
			(end 0.925 0.47)
			(stroke
				(width 0.05)
				(type default)
			)
			(fill no)
			(layer "F.CrtYd")
		)
		(fp_line
			(start 0.504 -0.25)
			(end 0.504 0.248)
			(stroke
				(width 0.15)
				(type solid)
			)
			(layer "F.Fab")
		)
		(fp_line
			(start -0.494 -0.25)
			(end 0.504 -0.25)
			(stroke
				(width 0.15)
				(type solid)
			)
			(layer "F.Fab")
		)
		(fp_line
			(start 0.504 0.248)
			(end -0.494 0.248)
			(stroke
				(width 0.15)
				(type solid)
			)
			(layer "F.Fab")
		)
		(fp_line
			(start -0.494 0.248)
			(end -0.494 -0.25)
			(stroke
				(width 0.15)
				(type solid)
			)
			(layer "F.Fab")
		)
		(pad "1" smd roundrect
			(at -0.48 0 90)
			(size 0.59 0.64)
			(layers "F.Cu" "F.Mask" "F.Paste")
			(roundrect_rratio 0.25)
			(net 1 "GND")
			(pintype "passive")
		)
		(pad "2" smd roundrect
			(at 0.48 0 90)
			(size 0.59 0.64)
			(layers "F.Cu" "F.Mask" "F.Paste")
			(roundrect_rratio 0.25)
			(net 2 "VCC3V3")
			(pintype "passive")
		)
	)
	(footprint "antmicro-footprints:C_0402_1005Metric"
		(layer "F.Cu")
		(at 121.305 116.415 -90)
		(descr "Capacitor SMD 0402")
		(tags "capacitor SMD 0402")
		(property "Reference" "C5"
			(at 0.985 -0.295 90)
			(layer "F.SilkS")
			(effects
				(font
					(size 0.7 0.7)
					(thickness 0.15)
				)
				(justify right bottom)
			)
		)
		(property "Value" "C_100n_0402"
			(at 0 1.4 90)
			(layer "F.Fab")
			(effects
				(font
					(size 0.7 0.7)
					(thickness 0.15)
				)
				(justify right bottom)
			)
		)
		(property "Datasheet" "https://www.murata.com/products/productdetail?partno=GRM155R61H104KE14%23"
			(at 0 0 270)
			(layer "F.Fab")
			(hide yes)
			(effects
				(font
					(size 1.27 1.27)
					(thickness 0.15)
				)
			)
		)
		(property "Description" "SMD Multilayer Ceramic Capacitor, 0.1 µF, 50 V, 0402 [1005 Metric], ± 10%, X5R, GRM Series"
			(at 0 0 270)
			(layer "F.Fab")
			(hide yes)
			(effects
				(font
					(size 1.27 1.27)
					(thickness 0.15)
				)
			)
		)
		(property "Author" "Antmicro"
			(at 4.89 237.72 0)
			(layer "F.Fab")
			(hide yes)
			(effects
				(font
					(size 1 1)
					(thickness 0.15)
				)
			)
		)
		(property "Dielectric" "X5R"
			(at 4.89 237.72 0)
			(layer "F.Fab")
			(hide yes)
			(effects
				(font
					(size 1 1)
					(thickness 0.15)
				)
			)
		)
		(property "License" "Apache-2.0"
			(at 4.89 237.72 0)
			(layer "F.Fab")
			(hide yes)
			(effects
				(font
					(size 1 1)
					(thickness 0.15)
				)
			)
		)
		(property "MPN" "GRM155R61H104KE14D"
			(at 4.89 237.72 0)
			(layer "F.Fab")
			(hide yes)
			(effects
				(font
					(size 1 1)
					(thickness 0.15)
				)
			)
		)
		(property "Manufacturer" "Murata"
			(at 4.89 237.72 0)
			(layer "F.Fab")
			(hide yes)
			(effects
				(font
					(size 1 1)
					(thickness 0.15)
				)
			)
		)
		(property "Val" "100n"
			(at 4.89 237.72 0)
			(layer "F.Fab")
			(hide yes)
			(effects
				(font
					(size 1 1)
					(thickness 0.15)
				)
			)
		)
		(property "Voltage" "50V"
			(at 4.89 237.72 0)
			(layer "F.Fab")
			(hide yes)
			(effects
				(font
					(size 1 1)
					(thickness 0.15)
				)
			)
		)
		(sheetname "/Interfaces/")
		(sheetfile "interfaces.kicad_sch")
		(attr smd)
		(fp_rect
			(start -0.925 -0.47)
			(end 0.925 0.47)
			(stroke
				(width 0.05)
				(type default)
			)
			(fill no)
			(layer "F.CrtYd")
		)
		(fp_line
			(start -0.494 0.248)
			(end -0.494 -0.25)
			(stroke
				(width 0.15)
				(type solid)
			)
			(layer "F.Fab")
		)
		(fp_line
			(start 0.504 0.248)
			(end -0.494 0.248)
			(stroke
				(width 0.15)
				(type solid)
			)
			(layer "F.Fab")
		)
		(fp_line
			(start -0.494 -0.25)
			(end 0.504 -0.25)
			(stroke
				(width 0.15)
				(type solid)
			)
			(layer "F.Fab")
		)
		(fp_line
			(start 0.504 -0.25)
			(end 0.504 0.248)
			(stroke
				(width 0.15)
				(type solid)
			)
			(layer "F.Fab")
		)
		(pad "1" smd roundrect
			(at -0.48 0 270)
			(size 0.59 0.64)
			(layers "F.Cu" "F.Mask" "F.Paste")
			(roundrect_rratio 0.25)
			(net 2 "VCC3V3")
			(pintype "passive")
		)
		(pad "2" smd roundrect
			(at 0.48 0 270)
			(size 0.59 0.64)
			(layers "F.Cu" "F.Mask" "F.Paste")
			(roundrect_rratio 0.25)
			(net 1 "GND")
			(pintype "passive")
		)
	)
)
